# S9S_MB_2U (Grand Teton) — schematic netlist excerpt (pin names and nets, part order shuffled) for the footprints in the layout excerpt that follows; sources: Cadence DE-HDL packaged netlist, KiCad conversion of 03242023_DA0F0TMBIJ0_F0T_Motherboard_J_brd_V01_OCP.brd

R327  Q_RES  10K 1% CHIP  pkg 0402LF  page 80 : A = P3V3_AUX ; B = FM_S3M_CPU1_CPLD_CONFIG_N
R703  Q_RES  10K 1% EMPTY  pkg 0402LF  page 130 : A = RST_PLD_CPU1_DRAM_AB_N ; B = GND

(kicad_pcb
	(version 20260206)
	(generator "pcbnew")
	(generator_version "10.0")
	(general
		(thickness 1.6)
		(legacy_teardrops no)
	)
	(paper "A4")
	(title_block
		(title "03242023_DA0F0TMBIJ0_F0T_Motherboard_J_brd_V01_OCP.brd")
		(comment 1 "Grand Teton / footprints 6005-6006 of 6105")
	)
	(layers
		(0 "F.Cu" signal "TOP")
		(4 "In1.Cu" signal "GND")
		(6 "In2.Cu" signal "IN1")
		(8 "In3.Cu" signal "GND1")
		(10 "In4.Cu" signal "IN2")
		(12 "In5.Cu" signal "GND2")
		(14 "In6.Cu" signal "IN3")
		(16 "In7.Cu" signal "GND3")
		(18 "In8.Cu" signal "VCC")
		(20 "In9.Cu" signal "VCC1")
		(22 "In10.Cu" signal "GND4")
		(24 "In11.Cu" signal "IN4")
		(26 "In12.Cu" signal "GND5")
		(28 "In13.Cu" signal "IN5")
		(30 "In14.Cu" signal "GND6")
		(32 "In15.Cu" signal "IN6")
		(34 "In16.Cu" signal "GND7")
		(2 "B.Cu" signal "BOTTOM")
		(9 "F.Adhes" user "F.Adhesive")
		(11 "B.Adhes" user "B.Adhesive")
		(13 "F.Paste" user "Package Geometry/Pastemask Top")
		(15 "B.Paste" user "Package Geometry/Pastemask Bottom")
		(5 "F.SilkS" user "Ref Des/Silkscreen Top")
		(7 "B.SilkS" user "Ref Des/Silkscreen Bottom")
		(1 "F.Mask" user "Board Geometry/Soldermask Top")
		(3 "B.Mask" user "Board Geometry/Soldermask Bottom")
		(17 "Dwgs.User" user "User.Drawings")
		(19 "Cmts.User" user "User.Comments")
		(21 "Eco1.User" user "User.Eco1")
		(23 "Eco2.User" user "User.Eco2")
		(25 "Edge.Cuts" user "Board Geometry/Outline")
		(27 "Margin" user)
		(31 "F.CrtYd" user "Package Geometry/Place Bound Top")
		(29 "B.CrtYd" user "Package Geometry/Place Bound Bottom")
		(35 "F.Fab" user "Ref Des/Assembly Top")
		(33 "B.Fab" user "Ref Des/Assembly Bottom")
	)
	(footprint ""
		(layer "B.Cu")
		(at 182.546752 -192.699894 -90)
		(property "Reference" "R327"
			(at 0 0 90)
			(layer "B.SilkS")
			(hide yes)
			(effects
				(font
					(size 1.27 1.27)
				)
				(justify mirror)
			)
		)
		(property "Value" ""
			(at 0 0 90)
			(layer "B.Fab")
			(effects
				(font
					(size 1.27 1.27)
				)
				(justify mirror)
			)
		)
		(duplicate_pad_numbers_are_jumpers no)
		(fp_line
			(start -0.7874 0.4064)
			(end 0.7874 0.4064)
			(stroke
				(width 0.1524)
				(type default)
			)
			(layer "B.SilkS")
		)
		(fp_line
			(start 0.7874 0.4064)
			(end 0.7874 -0.4064)
			(stroke
				(width 0.1524)
				(type default)
			)
			(layer "B.SilkS")
		)
		(fp_line
			(start -0.7874 -0.4064)
			(end -0.7874 0.4064)
			(stroke
				(width 0.1524)
				(type default)
			)
			(layer "B.SilkS")
		)
		(fp_line
			(start 0.7874 -0.4064)
			(end -0.7874 -0.4064)
			(stroke
				(width 0.1524)
				(type default)
			)
			(layer "B.SilkS")
		)
		(fp_line
			(start -0.67945 0.3048)
			(end -0.120396 0.3048)
			(stroke
				(width 0.1)
				(type default)
			)
			(layer "B.Fab")
		)
		(fp_line
			(start -0.120396 0.3048)
			(end -0.120396 0.2794)
			(stroke
				(width 0.1)
				(type default)
			)
			(layer "B.Fab")
		)
		(fp_line
			(start 0.12065 0.3048)
			(end 0.67945 0.3048)
			(stroke
				(width 0.1)
				(type default)
			)
			(layer "B.Fab")
		)
		(fp_line
			(start 0.67945 0.3048)
			(end 0.67945 -0.305054)
			(stroke
				(width 0.1)
				(type default)
			)
			(layer "B.Fab")
		)
		(fp_line
			(start -0.120396 0.2794)
			(end 0.12065 0.2794)
			(stroke
				(width 0.1)
				(type default)
			)
			(layer "B.Fab")
		)
		(fp_line
			(start 0.12065 0.2794)
			(end 0.12065 0.3048)
			(stroke
				(width 0.1)
				(type default)
			)
			(layer "B.Fab")
		)
		(fp_line
			(start -0.12065 -0.2794)
			(end -0.12065 -0.3048)
			(stroke
				(width 0.1)
				(type default)
			)
			(layer "B.Fab")
		)
		(fp_line
			(start 0.12065 -0.2794)
			(end -0.12065 -0.2794)
			(stroke
				(width 0.1)
				(type default)
			)
			(layer "B.Fab")
		)
		(fp_line
			(start -0.67945 -0.3048)
			(end -0.67945 0.3048)
			(stroke
				(width 0.1)
				(type default)
			)
			(layer "B.Fab")
		)
		(fp_line
			(start -0.12065 -0.3048)
			(end -0.67945 -0.3048)
			(stroke
				(width 0.1)
				(type default)
			)
			(layer "B.Fab")
		)
		(fp_line
			(start 0.12065 -0.305054)
			(end 0.12065 -0.2794)
			(stroke
				(width 0.1)
				(type default)
			)
			(layer "B.Fab")
		)
		(fp_line
			(start 0.67945 -0.305054)
			(end 0.12065 -0.305054)
			(stroke
				(width 0.1)
				(type default)
			)
			(layer "B.Fab")
		)
		(pad "1" smd circle
			(at 0.40005 0 90)
			(size 0 0)
			(layers "B.Cu" "B.Mask" "B.Paste")
			(net "P3V3_AUX")
		)
		(pad "2" smd circle
			(at -0.40005 0 90)
			(size 0 0)
			(layers "B.Cu" "B.Mask" "B.Paste")
			(net "FM_S3M_CPU1_CPLD_CONFIG_N")
		)
	)
	(footprint ""
		(layer "B.Cu")
		(at 35.567366 -192.924176 -90)
		(property "Reference" "R703"
			(at 0 0 90)
			(layer "B.SilkS")
			(hide yes)
			(effects
				(font
					(size 1.27 1.27)
				)
				(justify mirror)
			)
		)
		(property "Value" ""
			(at 0 0 90)
			(layer "B.Fab")
			(effects
				(font
					(size 1.27 1.27)
				)
				(justify mirror)
			)
		)
		(duplicate_pad_numbers_are_jumpers no)
		(fp_line
			(start -0.7874 0.4064)
			(end 0.7874 0.4064)
			(stroke
				(width 0.1524)
				(type default)
			)
			(layer "B.SilkS")
		)
		(fp_line
			(start 0.7874 0.4064)
			(end 0.7874 -0.4064)
			(stroke
				(width 0.1524)
				(type default)
			)
			(layer "B.SilkS")
		)
		(fp_line
			(start -0.7874 -0.4064)
			(end -0.7874 0.4064)
			(stroke
				(width 0.1524)
				(type default)
			)
			(layer "B.SilkS")
		)
		(fp_line
			(start 0.7874 -0.4064)
			(end -0.7874 -0.4064)
			(stroke
				(width 0.1524)
				(type default)
			)
			(layer "B.SilkS")
		)
		(fp_line
			(start -0.67945 0.3048)
			(end -0.120396 0.3048)
			(stroke
				(width 0.1)
				(type default)
			)
			(layer "B.Fab")
		)
		(fp_line
			(start -0.120396 0.3048)
			(end -0.120396 0.2794)
			(stroke
				(width 0.1)
				(type default)
			)
			(layer "B.Fab")
		)
		(fp_line
			(start 0.12065 0.3048)
			(end 0.67945 0.3048)
			(stroke
				(width 0.1)
				(type default)
			)
			(layer "B.Fab")
		)
		(fp_line
			(start 0.67945 0.3048)
			(end 0.67945 -0.305054)
			(stroke
				(width 0.1)
				(type default)
			)
			(layer "B.Fab")
		)
		(fp_line
			(start -0.120396 0.2794)
			(end 0.12065 0.2794)
			(stroke
				(width 0.1)
				(type default)
			)
			(layer "B.Fab")
		)
		(fp_line
			(start 0.12065 0.2794)
			(end 0.12065 0.3048)
			(stroke
				(width 0.1)
				(type default)
			)
			(layer "B.Fab")
		)
		(fp_line
			(start -0.12065 -0.2794)
			(end -0.12065 -0.3048)
			(stroke
				(width 0.1)
				(type default)
			)
			(layer "B.Fab")
		)
		(fp_line
			(start 0.12065 -0.2794)
			(end -0.12065 -0.2794)
			(stroke
				(width 0.1)
				(type default)
			)
			(layer "B.Fab")
		)
		(fp_line
			(start -0.67945 -0.3048)
			(end -0.67945 0.3048)
			(stroke
				(width 0.1)
				(type default)
			)
			(layer "B.Fab")
		)
		(fp_line
			(start -0.12065 -0.3048)
			(end -0.67945 -0.3048)
			(stroke
				(width 0.1)
				(type default)
			)
			(layer "B.Fab")
		)
		(fp_line
			(start 0.12065 -0.305054)
			(end 0.12065 -0.2794)
			(stroke
				(width 0.1)
				(type default)
			)
			(layer "B.Fab")
		)
		(fp_line
			(start 0.67945 -0.305054)
			(end 0.12065 -0.305054)
			(stroke
				(width 0.1)
				(type default)
			)
			(layer "B.Fab")
		)
		(pad "1" smd circle
			(at 0.40005 0 90)
			(size 0 0)
			(layers "B.Cu" "B.Mask" "B.Paste")
			(net "RST_PLD_CPU1_DRAM_AB_N")
		)
		(pad "2" smd circle
			(at -0.40005 0 90)
			(size 0 0)
			(layers "B.Cu" "B.Mask" "B.Paste")
			(net "GND")
		)
	)
)
